(kicad_pcb
	(version 20241229)
	(generator "pcbnew")
	(generator_version "9.0")
	(general
		(thickness 1.6296)
		(legacy_teardrops no)
	)
	(paper "A3")
	(title_block
		(title "Thunderbolt to 10GbE adapter")
		(date "2026-04-21")
		(rev "1.1.0")
		(company "Antmicro Ltd")
		(comment 1 "www.antmicro.com")
		(comment 9 "footprints 280-284 of 703")
	)
	(layers
		(0 "F.Cu" signal)
		(4 "In1.Cu" signal)
		(6 "In2.Cu" signal)
		(8 "In3.Cu" signal)
		(10 "In4.Cu" signal)
		(12 "In5.Cu" signal)
		(14 "In6.Cu" signal)
		(2 "B.Cu" signal)
		(9 "F.Adhes" user "F.Adhesive")
		(11 "B.Adhes" user "B.Adhesive")
		(13 "F.Paste" user)
		(15 "B.Paste" user)
		(5 "F.SilkS" user "F.Silkscreen")
		(7 "B.SilkS" user "B.Silkscreen")
		(1 "F.Mask" user)
		(3 "B.Mask" user)
		(17 "Dwgs.User" user "User.Drawings")
		(19 "Cmts.User" user "User.Comments")
		(21 "Eco1.User" user "User.Eco1")
		(23 "Eco2.User" user "User.Eco2")
		(25 "Edge.Cuts" user)
		(27 "Margin" user)
		(31 "F.CrtYd" user "F.Courtyard")
		(29 "B.CrtYd" user "B.Courtyard")
		(35 "F.Fab" user)
		(33 "B.Fab" user)
	)
	(footprint "antmicro-footprints:R_0603_1608Metric"
		(layer "F.Cu")
		(at 135.1 103.05 90)
		(descr "Resistor SMD 0603")
		(tags "resistor SMD 0603")
		(property "Reference" "R109"
			(at -17.649996 16.849997 90)
			(layer "F.SilkS")
			(effects
				(font
					(size 0.7 0.7)
					(thickness 0.15)
				)
			)
		)
		(property "Value" "R_0R_22.4A_0603"
			(at 0 1.6 90)
			(layer "F.Fab")
			(effects
				(font
					(size 0.7 0.7)
					(thickness 0.15)
				)
				(justify left bottom)
			)
		)
		(property "Datasheet" "https://fscdn.rohm.com/en/products/databook/datasheet/passive/resistor/chip_resistor/pmr-jpw-e.pdf"
			(at 0 0 90)
			(layer "F.Fab")
			(hide yes)
			(effects
				(font
					(size 1.27 1.27)
					(thickness 0.15)
				)
			)
		)
		(property "Description" "SMD Chip Resistor"
			(at 0 0 90)
			(layer "F.Fab")
			(hide yes)
			(effects
				(font
					(size 1.27 1.27)
					(thickness 0.15)
				)
			)
		)
		(property "MPN" "PMR03EZPJ000"
			(at 0 0 90)
			(unlocked yes)
			(layer "F.Fab")
			(hide yes)
			(effects
				(font
					(size 1 1)
					(thickness 0.15)
				)
			)
		)
		(property "Manufacturer" "ROHM Semiconductor"
			(at 0 0 90)
			(unlocked yes)
			(layer "F.Fab")
			(hide yes)
			(effects
				(font
					(size 1 1)
					(thickness 0.15)
				)
			)
		)
		(property "Val" "0R"
			(at 0 0 90)
			(unlocked yes)
			(layer "F.Fab")
			(hide yes)
			(effects
				(font
					(size 1 1)
					(thickness 0.15)
				)
			)
		)
		(property "Max. Curr." "22.4A"
			(at 0 0 90)
			(unlocked yes)
			(layer "F.Fab")
			(hide yes)
			(effects
				(font
					(size 1 1)
					(thickness 0.15)
				)
			)
		)
		(property "Author" "Antmicro"
			(at 0 0 90)
			(unlocked yes)
			(layer "F.Fab")
			(hide yes)
			(effects
				(font
					(size 1 1)
					(thickness 0.15)
				)
			)
		)
		(property "License" "Apache-2.0"
			(at 0 0 90)
			(unlocked yes)
			(layer "F.Fab")
			(hide yes)
			(effects
				(font
					(size 1 1)
					(thickness 0.15)
				)
			)
		)
		(property "Tolerance" "template_tolerance"
			(at 0 0 90)
			(unlocked yes)
			(layer "F.Fab")
			(hide yes)
			(effects
				(font
					(size 1 1)
					(thickness 0.15)
				)
			)
		)
		(sheetname "/X710 DCDC converters/")
		(sheetfile "DCDC_converters_X710.kicad_sch")
		(attr smd)
		(fp_line
			(start -0.15 -0.4)
			(end 0.15 -0.4)
			(stroke
				(width 0.15)
				(type solid)
			)
			(layer "F.SilkS")
		)
		(fp_line
			(start -0.15 0.4)
			(end 0.15 0.4)
			(stroke
				(width 0.15)
				(type solid)
			)
			(layer "F.SilkS")
		)
		(fp_rect
			(start -1.25 -0.65)
			(end 1.25 0.65)
			(stroke
				(width 0.05)
				(type solid)
			)
			(fill no)
			(layer "F.CrtYd")
		)
		(fp_rect
			(start -0.8 -0.4)
			(end 0.8 0.4)
			(stroke
				(width 0.15)
				(type solid)
			)
			(fill no)
			(layer "F.Fab")
		)
		(fp_text user "Author: Antmicro"
			(at -1.25 4.9 90)
			(layer "F.Fab")
			(effects
				(font
					(size 0.7 0.7)
					(thickness 0.15)
				)
				(justify left bottom)
			)
		)
		(fp_text user "${REFERENCE}"
			(at -1.25 3.898 90)
			(layer "F.Fab")
			(effects
				(font
					(size 0.7 0.7)
					(thickness 0.15)
				)
				(justify left bottom)
			)
		)
		(fp_text user "License: Apache-2.0"
			(at -1.25 5.9 90)
			(layer "F.Fab")
			(effects
				(font
					(size 0.7 0.7)
					(thickness 0.15)
				)
				(justify left bottom)
			)
		)
		(pad "1" smd roundrect
			(at -0.7 0 90)
			(size 0.8 1)
			(layers "F.Cu" "F.Mask" "F.Paste")
			(roundrect_rratio 0.2)
			(net 335 "/X710 DCDC converters/+VCCD_OUT")
			(pintype "passive")
		)
		(pad "2" smd roundrect
			(at 0.7 0 90)
			(size 0.8 1)
			(layers "F.Cu" "F.Mask" "F.Paste")
			(roundrect_rratio 0.2)
			(net 9 "VCCD")
			(pintype "passive")
		)
	)
	(footprint "antmicro-footprints:R_0402_1005Metric"
		(layer "F.Cu")
		(at 157.155 65.174999 -90)
		(descr "Resistor SMD 0402")
		(tags "resistor SMD 0402")
		(property "Reference" "R147"
			(at -2.374999 -0.095001 270)
			(layer "F.SilkS")
			(effects
				(font
					(size 0.7 0.7)
					(thickness 0.15)
				)
			)
		)
		(property "Value" "R_100k_0402"
			(at -1.011843 1.772047 270)
			(layer "F.Fab")
			(effects
				(font
					(size 0.7 0.7)
					(thickness 0.15)
				)
				(justify left bottom)
			)
		)
		(property "Datasheet" "https://www.bourns.com/docs/product-datasheets/cr.pdf"
			(at 0 0 270)
			(layer "F.Fab")
			(hide yes)
			(effects
				(font
					(size 1.27 1.27)
					(thickness 0.15)
				)
			)
		)
		(property "Description" "SMD Chip Resistor, 100 kohm, ± 1%, 62.5 mW, 0402 [1005 Metric], Thick Film, General Purpose"
			(at 0 0 270)
			(layer "F.Fab")
			(hide yes)
			(effects
				(font
					(size 1.27 1.27)
					(thickness 0.15)
				)
			)
		)
		(property "MPN" "CR0402-FX-1003GLF"
			(at 0 0 270)
			(unlocked yes)
			(layer "F.Fab")
			(hide yes)
			(effects
				(font
					(size 1 1)
					(thickness 0.15)
				)
			)
		)
		(property "Manufacturer" "Bourns"
			(at 0 0 270)
			(unlocked yes)
			(layer "F.Fab")
			(hide yes)
			(effects
				(font
					(size 1 1)
					(thickness 0.15)
				)
			)
		)
		(property "License" "Apache-2.0"
			(at 0 0 270)
			(unlocked yes)
			(layer "F.Fab")
			(hide yes)
			(effects
				(font
					(size 1 1)
					(thickness 0.15)
				)
			)
		)
		(property "Author" "Antmicro"
			(at 0 0 270)
			(unlocked yes)
			(layer "F.Fab")
			(hide yes)
			(effects
				(font
					(size 1 1)
					(thickness 0.15)
				)
			)
		)
		(property "Val" "100k"
			(at 0 0 270)
			(unlocked yes)
			(layer "F.Fab")
			(hide yes)
			(effects
				(font
					(size 1 1)
					(thickness 0.15)
				)
			)
		)
		(property "Tolerance" "1%"
			(at 0 0 270)
			(unlocked yes)
			(layer "F.Fab")
			(hide yes)
			(effects
				(font
					(size 1 1)
					(thickness 0.15)
				)
			)
		)
		(sheetname "/X710-AT2 Misc/")
		(sheetfile "x710-at2-mics.kicad_sch")
		(attr smd)
		(fp_rect
			(start -0.925 -0.47)
			(end 0.925 0.47)
			(stroke
				(width 0.05)
				(type default)
			)
			(fill no)
			(layer "F.CrtYd")
		)
		(fp_rect
			(start -0.5 -0.25)
			(end 0.5 0.25)
			(stroke
				(width 0.15)
				(type solid)
			)
			(fill no)
			(layer "F.Fab")
		)
		(fp_text user "License: Apache-2.0"
			(at -0.95 5.169 270)
			(layer "F.Fab")
			(effects
				(font
					(size 0.7 0.7)
					(thickness 0.15)
				)
				(justify left bottom)
			)
		)
		(fp_text user "${REFERENCE}"
			(at -0.95 3.168 270)
			(layer "F.Fab")
			(effects
				(font
					(size 0.7 0.7)
					(thickness 0.15)
				)
				(justify left bottom)
			)
		)
		(fp_text user "Author: Antmicro"
			(at -0.95 4.169 270)
			(layer "F.Fab")
			(effects
				(font
					(size 0.7 0.7)
					(thickness 0.15)
				)
				(justify left bottom)
			)
		)
		(pad "1" smd roundrect
			(at -0.48 0 270)
			(size 0.59 0.64)
			(layers "F.Cu" "F.Mask" "F.Paste")
			(roundrect_rratio 0.25)
			(net 138 "/X710-AT2 Misc/NCSI.TXD_1")
			(pintype "passive")
		)
		(pad "2" smd roundrect
			(at 0.48 0 270)
			(size 0.59 0.64)
			(layers "F.Cu" "F.Mask" "F.Paste")
			(roundrect_rratio 0.25)
			(net 7 "+3V3")
			(pintype "passive")
		)
	)
	(footprint "antmicro-footprints:R_0402_1005Metric"
		(layer "F.Cu")
		(at 170.6 72.1 -90)
		(descr "Resistor SMD 0402")
		(tags "resistor SMD 0402")
		(property "Reference" "R201"
			(at -0.9 -0.4 270)
			(layer "F.SilkS")
			(effects
				(font
					(size 0.7 0.7)
					(thickness 0.15)
				)
				(justify left bottom)
			)
		)
		(property "Value" "R_3k3_0402"
			(at -1.011843 1.772047 270)
			(layer "F.Fab")
			(effects
				(font
					(size 0.7 0.7)
					(thickness 0.15)
				)
				(justify left bottom)
			)
		)
		(property "Datasheet" "https://www.bourns.com/docs/product-datasheets/cr.pdf"
			(at 0 0 270)
			(layer "F.Fab")
			(hide yes)
			(effects
				(font
					(size 1.27 1.27)
					(thickness 0.15)
				)
			)
		)
		(property "Description" "SMD Chip Resistor, 3.3 kohm, ± 1%, 63 mW, 0402 [1005 Metric], Thick Film, General Purpose"
			(at 0 0 270)
			(layer "F.Fab")
			(hide yes)
			(effects
				(font
					(size 1.27 1.27)
					(thickness 0.15)
				)
			)
		)
		(property "MPN" "CR0402-FX-3301GLF"
			(at 0 0 270)
			(unlocked yes)
			(layer "F.Fab")
			(hide yes)
			(effects
				(font
					(size 1 1)
					(thickness 0.15)
				)
			)
		)
		(property "Manufacturer" "Bourns"
			(at 0 0 270)
			(unlocked yes)
			(layer "F.Fab")
			(hide yes)
			(effects
				(font
					(size 1 1)
					(thickness 0.15)
				)
			)
		)
		(property "License" "Apache-2.0"
			(at 0 0 270)
			(unlocked yes)
			(layer "F.Fab")
			(hide yes)
			(effects
				(font
					(size 1 1)
					(thickness 0.15)
				)
			)
		)
		(property "Author" "Antmicro"
			(at 0 0 270)
			(unlocked yes)
			(layer "F.Fab")
			(hide yes)
			(effects
				(font
					(size 1 1)
					(thickness 0.15)
				)
			)
		)
		(property "Val" "3k3"
			(at 0 0 270)
			(unlocked yes)
			(layer "F.Fab")
			(hide yes)
			(effects
				(font
					(size 1 1)
					(thickness 0.15)
				)
			)
		)
		(property "Tolerance" "1%"
			(at 0 0 270)
			(unlocked yes)
			(layer "F.Fab")
			(hide yes)
			(effects
				(font
					(size 1 1)
					(thickness 0.15)
				)
			)
		)
		(sheetname "/X710-AT2 10GbE/")
		(sheetfile "x710-at2-10gbe.kicad_sch")
		(attr smd)
		(fp_rect
			(start -0.925 -0.47)
			(end 0.925 0.47)
			(stroke
				(width 0.05)
				(type default)
			)
			(fill no)
			(layer "F.CrtYd")
		)
		(fp_rect
			(start -0.5 -0.25)
			(end 0.5 0.25)
			(stroke
				(width 0.15)
				(type solid)
			)
			(fill no)
			(layer "F.Fab")
		)
		(fp_text user "License: Apache-2.0"
			(at -0.95 5.169 270)
			(layer "F.Fab")
			(effects
				(font
					(size 0.7 0.7)
					(thickness 0.15)
				)
				(justify left bottom)
			)
		)
		(fp_text user "${REFERENCE}"
			(at -0.95 3.168 270)
			(layer "F.Fab")
			(effects
				(font
					(size 0.7 0.7)
					(thickness 0.15)
				)
				(justify left bottom)
			)
		)
		(fp_text user "Author: Antmicro"
			(at -0.95 4.169 270)
			(layer "F.Fab")
			(effects
				(font
					(size 0.7 0.7)
					(thickness 0.15)
				)
				(justify left bottom)
			)
		)
		(pad "1" smd roundrect
			(at -0.48 0 270)
			(size 0.59 0.64)
			(layers "F.Cu" "F.Mask" "F.Paste")
			(roundrect_rratio 0.25)
			(net 102 "/X710-AT2 10GbE/MDIO0_SDA0")
			(pintype "passive")
		)
		(pad "2" smd roundrect
			(at 0.48 0 270)
			(size 0.59 0.64)
			(layers "F.Cu" "F.Mask" "F.Paste")
			(roundrect_rratio 0.25)
			(net 7 "+3V3")
			(pintype "passive")
		)
	)
	(footprint "antmicro-footprints:C_0402_1005Metric"
		(layer "F.Cu")
		(at 124 70 180)
		(descr "Capacitor SMD 0402")
		(tags "capacitor SMD 0402")
		(property "Reference" "C74"
			(at -1 0.2 180)
			(layer "F.SilkS")
			(effects
				(font
					(size 0.7 0.7)
					(thickness 0.15)
				)
				(justify left bottom)
			)
		)
		(property "Value" "C_100n_0402"
			(at -1.022927 2.155213 180)
			(layer "F.Fab")
			(effects
				(font
					(size 0.7 0.7)
					(thickness 0.15)
				)
				(justify left bottom)
			)
		)
		(property "Datasheet" "https://www.murata.com/products/productdetail?partno=GRM155R61H104KE14%23"
			(at 0 0 180)
			(layer "F.Fab")
			(hide yes)
			(effects
				(font
					(size 1.27 1.27)
					(thickness 0.15)
				)
			)
		)
		(property "Description" "SMD Multilayer Ceramic Capacitor, 0.1 µF, 50 V, 0402 [1005 Metric], ± 10%, X5R, GRM Series"
			(at 0 0 180)
			(layer "F.Fab")
			(hide yes)
			(effects
				(font
					(size 1.27 1.27)
					(thickness 0.15)
				)
			)
		)
		(property "MPN" "GRM155R61H104KE14D"
			(at 0 0 180)
			(unlocked yes)
			(layer "F.Fab")
			(hide yes)
			(effects
				(font
					(size 1 1)
					(thickness 0.15)
				)
			)
		)
		(property "Manufacturer" "Murata"
			(at 0 0 180)
			(unlocked yes)
			(layer "F.Fab")
			(hide yes)
			(effects
				(font
					(size 1 1)
					(thickness 0.15)
				)
			)
		)
		(property "License" "Apache-2.0"
			(at 0 0 180)
			(unlocked yes)
			(layer "F.Fab")
			(hide yes)
			(effects
				(font
					(size 1 1)
					(thickness 0.15)
				)
			)
		)
		(property "Author" "Antmicro"
			(at 0 0 180)
			(unlocked yes)
			(layer "F.Fab")
			(hide yes)
			(effects
				(font
					(size 1 1)
					(thickness 0.15)
				)
			)
		)
		(property "Val" "100n"
			(at 0 0 180)
			(unlocked yes)
			(layer "F.Fab")
			(hide yes)
			(effects
				(font
					(size 1 1)
					(thickness 0.15)
				)
			)
		)
		(property "Voltage" "50V"
			(at 0 0 180)
			(unlocked yes)
			(layer "F.Fab")
			(hide yes)
			(effects
				(font
					(size 1 1)
					(thickness 0.15)
				)
			)
		)
		(property "Dielectric" "X5R"
			(at 0 0 180)
			(unlocked yes)
			(layer "F.Fab")
			(hide yes)
			(effects
				(font
					(size 1 1)
					(thickness 0.15)
				)
			)
		)
		(sheetname "/Fan controller/")
		(sheetfile "fan-controller.kicad_sch")
		(attr smd)
		(fp_rect
			(start -0.925 -0.47)
			(end 0.925 0.47)
			(stroke
				(width 0.05)
				(type default)
			)
			(fill no)
			(layer "F.CrtYd")
		)
		(fp_line
			(start 0.504 0.248)
			(end -0.494 0.248)
			(stroke
				(width 0.15)
				(type solid)
			)
			(layer "F.Fab")
		)
		(fp_line
			(start 0.504 -0.25)
			(end 0.504 0.248)
			(stroke
				(width 0.15)
				(type solid)
			)
			(layer "F.Fab")
		)
		(fp_line
			(start -0.494 0.248)
			(end -0.494 -0.25)
			(stroke
				(width 0.15)
				(type solid)
			)
			(layer "F.Fab")
		)
		(fp_line
			(start -0.494 -0.25)
			(end 0.504 -0.25)
			(stroke
				(width 0.15)
				(type solid)
			)
			(layer "F.Fab")
		)
		(fp_text user "License: Apache-2.0"
			(at -0.939 5.799 180)
			(layer "F.Fab")
			(effects
				(font
					(size 0.7 0.7)
					(thickness 0.15)
				)
				(justify left bottom)
			)
		)
		(fp_text user "Author: Antmicro"
			(at -0.939 3.399 180)
			(layer "F.Fab")
			(effects
				(font
					(size 0.7 0.7)
					(thickness 0.15)
				)
				(justify left bottom)
			)
		)
		(fp_text user "${REFERENCE}"
			(at -0.939 4.599 180)
			(layer "F.Fab")
			(effects
				(font
					(size 0.7 0.7)
					(thickness 0.15)
				)
				(justify left bottom)
			)
		)
		(pad "1" smd roundrect
			(at -0.48 0 180)
			(size 0.59 0.64)
			(layers "F.Cu" "F.Mask" "F.Paste")
			(roundrect_rratio 0.25)
			(net 23 "GND")
			(pintype "passive")
		)
		(pad "2" smd roundrect
			(at 0.48 0 180)
			(size 0.59 0.64)
			(layers "F.Cu" "F.Mask" "F.Paste")
			(roundrect_rratio 0.25)
			(net 40 "+5V")
			(pintype "passive")
		)
	)
	(footprint "antmicro-footprints:C_0603_1608Metric_EIA"
		(layer "F.Cu")
		(at 136.450001 103.050001 -90)
		(descr "Capacitor SMD 0603, IPC-7351 Density Level A")
		(tags "Capacitor 0603")
		(property "Reference" "C140"
			(at 17.649996 -16.849997 270)
			(layer "F.SilkS")
			(effects
				(font
					(size 0.7 0.7)
					(thickness 0.15)
				)
			)
		)
		(property "Value" "C_22u_16V_0603"
			(at -1.42757 1.770288 270)
			(layer "F.Fab")
			(effects
				(font
					(size 0.7 0.7)
					(thickness 0.15)
				)
				(justify left bottom)
			)
		)
		(property "Datasheet" "https://product.samsungsem.com/mlcc/CL10A226MO7JZN.do"
			(at 0 0 270)
			(layer "F.Fab")
			(hide yes)
			(effects
				(font
					(size 1.27 1.27)
					(thickness 0.15)
				)
			)
		)
		(property "Description" "SMD Multilayer Ceramic Capacitor"
			(at 0 0 270)
			(layer "F.Fab")
			(hide yes)
			(effects
				(font
					(size 1.27 1.27)
					(thickness 0.15)
				)
			)
		)
		(property "MPN" "CL10A226MO7JZNC"
			(at 0 0 270)
			(unlocked yes)
			(layer "F.Fab")
			(hide yes)
			(effects
				(font
					(size 1 1)
					(thickness 0.15)
				)
			)
		)
		(property "Manufacturer" "Samsung Electro-Mechanics"
			(at 0 0 270)
			(unlocked yes)
			(layer "F.Fab")
			(hide yes)
			(effects
				(font
					(size 1 1)
					(thickness 0.15)
				)
			)
		)
		(property "License" "Apache-2.0"
			(at 0 0 270)
			(unlocked yes)
			(layer "F.Fab")
			(hide yes)
			(effects
				(font
					(size 1 1)
					(thickness 0.15)
				)
			)
		)
		(property "Author" "Antmicro"
			(at 0 0 270)
			(unlocked yes)
			(layer "F.Fab")
			(hide yes)
			(effects
				(font
					(size 1 1)
					(thickness 0.15)
				)
			)
		)
		(property "Val" "22u"
			(at 0 0 270)
			(unlocked yes)
			(layer "F.Fab")
			(hide yes)
			(effects
				(font
					(size 1 1)
					(thickness 0.15)
				)
			)
		)
		(property "Voltage" "16V"
			(at 0 0 270)
			(unlocked yes)
			(layer "F.Fab")
			(hide yes)
			(effects
				(font
					(size 1 1)
					(thickness 0.15)
				)
			)
		)
		(property "Dielectric" ""
			(at 0 0 270)
			(unlocked yes)
			(layer "F.Fab")
			(hide yes)
			(effects
				(font
					(size 1 1)
					(thickness 0.15)
				)
			)
		)
		(sheetname "/X710 DCDC converters/")
		(sheetfile "DCDC_converters_X710.kicad_sch")
		(attr smd)
		(fp_line
			(start -0.15 0.55)
			(end 0.15 0.55)
			(stroke
				(width 0.15)
				(type solid)
			)
			(layer "F.SilkS")
		)
		(fp_line
			(start -0.15 -0.55)
			(end 0.15 -0.55)
			(stroke
				(width 0.15)
				(type solid)
			)
			(layer "F.SilkS")
		)
		(fp_rect
			(start -1.25 -0.65)
			(end 1.25 0.65)
			(stroke
				(width 0.05)
				(type solid)
			)
			(fill no)
			(layer "F.CrtYd")
		)
		(fp_rect
			(start -0.8 -0.45)
			(end 0.8 0.45)
			(stroke
				(width 0.15)
				(type solid)
			)
			(fill no)
			(layer "F.Fab")
		)
		(fp_text user "Author: Antmicro"
			(at -1.682 4.894 270)
			(layer "F.Fab")
			(effects
				(font
					(size 0.7 0.7)
					(thickness 0.15)
				)
				(justify left bottom)
			)
		)
		(fp_text user "License: Apache-2.0"
			(at -1.682 5.895 270)
			(layer "F.Fab")
			(effects
				(font
					(size 0.7 0.7)
					(thickness 0.15)
				)
				(justify left bottom)
			)
		)
		(fp_text user "${REFERENCE}"
			(at -1.682 3.895 270)
			(layer "F.Fab")
			(effects
				(font
					(size 0.7 0.7)
					(thickness 0.15)
				)
				(justify left bottom)
			)
		)
		(pad "1" smd roundrect
			(at -0.7 0 270)
			(size 0.8 1.1)
			(layers "F.Cu" "F.Mask" "F.Paste")
			(roundrect_rratio 0.2)
			(net 23 "GND")
			(pintype "passive")
		)
		(pad "2" smd roundrect
			(at 0.7 0 270)
			(size 0.8 1.1)
			(layers "F.Cu" "F.Mask" "F.Paste")
			(roundrect_rratio 0.2)
			(net 335 "/X710 DCDC converters/+VCCD_OUT")
			(pintype "passive")
		)
	)
)
